#ISCELL
  cls sheet_a1 *
  *
#CELL
  passive resistor *
  page515_i122
#ISCELL
  cls offpage_in *
  page515_i123
#ISCELL
  cls vcc *
  page515_i124
#ISCELL
  cls gnd_sg *
  page515_i126
#CELL
  passive resistor *
  page515_i127
#CELL
  passive capacitor *
  page515_i128
#CELL
  passive resistor *
  page515_i129
#CELL
  passive capacitor *
  page515_i130
#ISCELL
  cls gnd_sg *
  page515_i131
#CELL
  passive capacitor *
  page515_i132
#ISCELL
  cls gnd_sg *
  page515_i133
#CELL
  passive capacitor *
  page515_i134
#CELL
  passive ferritebead *
  page515_i135
#ISCELL
  cls gnd_sg *
  page515_i136
#ISCELL
  cls gnd_sg *
  page515_i137
#CELL
  passive capacitor *
  page515_i138
#CELL
  passive resistor *
  page515_i139
#CELL
  passive resistor *
  page515_i140
#ISCELL
  cls offpage_out *
  page515_i142
#CELL
  passive resistor *
  page515_i143
#ISCELL
  cls gnd_sg *
  page515_i144
#CELL
  passive resistor *
  page515_i145
#CELL
  passive resistor *
  page515_i146
#CELL
  passive capacitor *
  page515_i147
#ISCELL
  cls gnd_sg *
  page515_i148
#CELL
  passive capacitor *
  page515_i149
#ISCELL
  cls vcc *
  page515_i150
#CELL
  analog isl80101irajz_dfn10 *
  page515_i151
#CELL
  passive resistor *
  page515_i152
#ISCELL
  cls gnd_sg *
  page515_i153
#CELL
  passive capacitor *
  page515_i154
#CELL
  passive capacitor *
  page515_i155
#ISCELL
  cls vcc *
  page515_i163
#ISCELL
  cls vcc *
  page515_i164
#ISCELL
  cls offpage_out *
  page515_i166
#CELL
  passive resistor *
  page515_i167
#CELL
  passive capacitor *
  page515_i168
#CELL
  passive capacitor *
  page515_i169
#ISCELL
  cls gnd_sg *
  page515_i55
#CELL
  passive resistor *
  page515_i56
#ISCELL
  cls offpage_in *
  page515_i58
#ISCELL
  cls gnd_sg *
  page515_i60
#CELL
  passive capacitor *
  page515_i61
#CELL
  passive capacitor *
  page515_i63
#CELL
  passive capacitor *
  page515_i64
#ISCELL
  cls gnd_sg *
  page515_i65
#CELL
  passive capacitor *
  page515_i66
#CELL
  passive resistor *
  page515_i67
#CELL
  passive resistor *
  page515_i69
#CELL
  passive capacitor *
  page515_i71
#CELL
  passive capacitor *
  page515_i72
#ISCELL
  cls gnd_sg *
  page515_i73
#CELL
  passive capacitor *
  page515_i74
#ISCELL
  cls vcc *
  page515_i75
#CELL
  analog ncp45560imntwg_h_dfn12 *
  page515_i76
#ISCELL
  cls gnd_sg *
  page515_i77
#CELL
  passive capacitor *
  page515_i80
#CELL
  passive capacitor *
  page515_i81
#CELL
  analog ncp45560imntwg_h_dfn12 *
  page515_i82
#ISCELL
  cls vcc *
  page515_i83
#ISCELL
  cls vcc *
  page515_i85
#ISCELL
  cls vcc *
  page515_i86
#CELL
  passive capacitor *
  page515_i87
